# S9S_MB_2U (Grand Teton) — schematic netlist excerpt (pin names and nets, part order shuffled) for the footprints in the layout excerpt that follows; sources: Cadence DE-HDL packaged netlist, KiCad conversion of 03242023_DA0F0TMBIJ0_F0T_Motherboard_J_brd_V01_OCP.brd

PR371  Q_RES  0 5% CHIP  pkg 0402LF  page 278 : A = SH_PVCCD_HV_CPU0 ; B = SH_PVCCD_HV_CPU0_R
PC199_P0_1  Q_CAP  100NF 50V 10% X7R  pkg C0402  page 275 : A = PVCCINFAON_CPU0 ; B = GND

(kicad_pcb
	(version 20260206)
	(generator "pcbnew")
	(generator_version "10.0")
	(general
		(thickness 1.6)
		(legacy_teardrops no)
	)
	(paper "A4")
	(title_block
		(title "03242023_DA0F0TMBIJ0_F0T_Motherboard_J_brd_V01_OCP.brd")
		(comment 1 "Grand Teton / footprints 1776-1777 of 6105")
	)
	(layers
		(0 "F.Cu" signal "TOP")
		(4 "In1.Cu" signal "GND")
		(6 "In2.Cu" signal "IN1")
		(8 "In3.Cu" signal "GND1")
		(10 "In4.Cu" signal "IN2")
		(12 "In5.Cu" signal "GND2")
		(14 "In6.Cu" signal "IN3")
		(16 "In7.Cu" signal "GND3")
		(18 "In8.Cu" signal "VCC")
		(20 "In9.Cu" signal "VCC1")
		(22 "In10.Cu" signal "GND4")
		(24 "In11.Cu" signal "IN4")
		(26 "In12.Cu" signal "GND5")
		(28 "In13.Cu" signal "IN5")
		(30 "In14.Cu" signal "GND6")
		(32 "In15.Cu" signal "IN6")
		(34 "In16.Cu" signal "GND7")
		(2 "B.Cu" signal "BOTTOM")
		(9 "F.Adhes" user "F.Adhesive")
		(11 "B.Adhes" user "B.Adhesive")
		(13 "F.Paste" user "Package Geometry/Pastemask Top")
		(15 "B.Paste" user "Package Geometry/Pastemask Bottom")
		(5 "F.SilkS" user "Ref Des/Silkscreen Top")
		(7 "B.SilkS" user "Ref Des/Silkscreen Bottom")
		(1 "F.Mask" user "Board Geometry/Soldermask Top")
		(3 "B.Mask" user "Board Geometry/Soldermask Bottom")
		(17 "Dwgs.User" user "User.Drawings")
		(19 "Cmts.User" user "User.Comments")
		(21 "Eco1.User" user "User.Eco1")
		(23 "Eco2.User" user "User.Eco2")
		(25 "Edge.Cuts" user "Board Geometry/Outline")
		(27 "Margin" user)
		(31 "F.CrtYd" user "Package Geometry/Place Bound Top")
		(29 "B.CrtYd" user "Package Geometry/Place Bound Bottom")
		(35 "F.Fab" user "Ref Des/Assembly Top")
		(33 "B.Fab" user "Ref Des/Assembly Bottom")
	)
	(footprint ""
		(layer "F.Cu")
		(at 436.292244 -127.248158 -90)
		(property "Reference" "PR371"
			(at 0 0 270)
			(layer "F.SilkS")
			(hide yes)
			(effects
				(font
					(size 1.27 1.27)
				)
			)
		)
		(property "Value" ""
			(at 0 0 270)
			(layer "F.Fab")
			(effects
				(font
					(size 1.27 1.27)
				)
			)
		)
		(duplicate_pad_numbers_are_jumpers no)
		(fp_line
			(start -0.7874 0.4064)
			(end -0.7874 -0.4064)
			(stroke
				(width 0.1524)
				(type default)
			)
			(layer "F.SilkS")
		)
		(fp_line
			(start 0.7874 0.4064)
			(end -0.7874 0.4064)
			(stroke
				(width 0.1524)
				(type default)
			)
			(layer "F.SilkS")
		)
		(fp_line
			(start -0.7874 -0.4064)
			(end 0.7874 -0.4064)
			(stroke
				(width 0.1524)
				(type default)
			)
			(layer "F.SilkS")
		)
		(fp_line
			(start 0.7874 -0.4064)
			(end 0.7874 0.4064)
			(stroke
				(width 0.1524)
				(type default)
			)
			(layer "F.SilkS")
		)
		(fp_line
			(start -0.67945 0.3048)
			(end -0.67945 -0.305054)
			(stroke
				(width 0.1)
				(type default)
			)
			(layer "F.Fab")
		)
		(fp_line
			(start -0.12065 0.3048)
			(end -0.67945 0.3048)
			(stroke
				(width 0.1)
				(type default)
			)
			(layer "F.Fab")
		)
		(fp_line
			(start 0.120396 0.3048)
			(end 0.120396 0.2794)
			(stroke
				(width 0.1)
				(type default)
			)
			(layer "F.Fab")
		)
		(fp_line
			(start 0.67945 0.3048)
			(end 0.120396 0.3048)
			(stroke
				(width 0.1)
				(type default)
			)
			(layer "F.Fab")
		)
		(fp_line
			(start -0.12065 0.2794)
			(end -0.12065 0.3048)
			(stroke
				(width 0.1)
				(type default)
			)
			(layer "F.Fab")
		)
		(fp_line
			(start 0.120396 0.2794)
			(end -0.12065 0.2794)
			(stroke
				(width 0.1)
				(type default)
			)
			(layer "F.Fab")
		)
		(fp_line
			(start -0.12065 -0.2794)
			(end 0.12065 -0.2794)
			(stroke
				(width 0.1)
				(type default)
			)
			(layer "F.Fab")
		)
		(fp_line
			(start 0.12065 -0.2794)
			(end 0.12065 -0.3048)
			(stroke
				(width 0.1)
				(type default)
			)
			(layer "F.Fab")
		)
		(fp_line
			(start 0.12065 -0.3048)
			(end 0.67945 -0.3048)
			(stroke
				(width 0.1)
				(type default)
			)
			(layer "F.Fab")
		)
		(fp_line
			(start 0.67945 -0.3048)
			(end 0.67945 0.3048)
			(stroke
				(width 0.1)
				(type default)
			)
			(layer "F.Fab")
		)
		(fp_line
			(start -0.67945 -0.305054)
			(end -0.12065 -0.305054)
			(stroke
				(width 0.1)
				(type default)
			)
			(layer "F.Fab")
		)
		(fp_line
			(start -0.12065 -0.305054)
			(end -0.12065 -0.2794)
			(stroke
				(width 0.1)
				(type default)
			)
			(layer "F.Fab")
		)
		(pad "1" smd circle
			(at -0.40005 0 270)
			(size 0 0)
			(layers "F.Cu" "F.Mask" "F.Paste")
			(net "SH_PVCCD_HV_CPU0")
		)
		(pad "2" smd circle
			(at 0.40005 0 270)
			(size 0 0)
			(layers "F.Cu" "F.Mask" "F.Paste")
			(net "SH_PVCCD_HV_CPU0_R")
		)
	)
	(footprint ""
		(layer "F.Cu")
		(at 407.40584 -183.535828)
		(property "Reference" "PC199_P0_1"
			(at 0 0 0)
			(layer "F.SilkS")
			(hide yes)
			(effects
				(font
					(size 1.27 1.27)
				)
			)
		)
		(property "Value" ""
			(at 0 0 0)
			(layer "F.Fab")
			(effects
				(font
					(size 1.27 1.27)
				)
			)
		)
		(duplicate_pad_numbers_are_jumpers no)
		(fp_line
			(start -0.7874 -0.4064)
			(end 0.7874 -0.4064)
			(stroke
				(width 0.1524)
				(type default)
			)
			(layer "F.SilkS")
		)
		(fp_line
			(start -0.7874 0.4064)
			(end -0.7874 -0.4064)
			(stroke
				(width 0.1524)
				(type default)
			)
			(layer "F.SilkS")
		)
		(fp_line
			(start 0.7874 -0.4064)
			(end 0.7874 0.4064)
			(stroke
				(width 0.1524)
				(type default)
			)
			(layer "F.SilkS")
		)
		(fp_line
			(start 0.7874 0.4064)
			(end -0.7874 0.4064)
			(stroke
				(width 0.1524)
				(type default)
			)
			(layer "F.SilkS")
		)
		(fp_line
			(start -0.67945 -0.305054)
			(end -0.12065 -0.305054)
			(stroke
				(width 0.1)
				(type default)
			)
			(layer "F.Fab")
		)
		(fp_line
			(start -0.67945 0.3048)
			(end -0.67945 -0.305054)
			(stroke
				(width 0.1)
				(type default)
			)
			(layer "F.Fab")
		)
		(fp_line
			(start -0.12065 -0.305054)
			(end -0.12065 -0.2794)
			(stroke
				(width 0.1)
				(type default)
			)
			(layer "F.Fab")
		)
		(fp_line
			(start -0.12065 -0.2794)
			(end 0.12065 -0.2794)
			(stroke
				(width 0.1)
				(type default)
			)
			(layer "F.Fab")
		)
		(fp_line
			(start -0.12065 0.2794)
			(end -0.12065 0.3048)
			(stroke
				(width 0.1)
				(type default)
			)
			(layer "F.Fab")
		)
		(fp_line
			(start -0.12065 0.3048)
			(end -0.67945 0.3048)
			(stroke
				(width 0.1)
				(type default)
			)
			(layer "F.Fab")
		)
		(fp_line
			(start 0.120396 0.2794)
			(end -0.12065 0.2794)
			(stroke
				(width 0.1)
				(type default)
			)
			(layer "F.Fab")
		)
		(fp_line
			(start 0.120396 0.3048)
			(end 0.120396 0.2794)
			(stroke
				(width 0.1)
				(type default)
			)
			(layer "F.Fab")
		)
		(fp_line
			(start 0.12065 -0.3048)
			(end 0.67945 -0.3048)
			(stroke
				(width 0.1)
				(type default)
			)
			(layer "F.Fab")
		)
		(fp_line
			(start 0.12065 -0.2794)
			(end 0.12065 -0.3048)
			(stroke
				(width 0.1)
				(type default)
			)
			(layer "F.Fab")
		)
		(fp_line
			(start 0.67945 -0.3048)
			(end 0.67945 0.3048)
			(stroke
				(width 0.1)
				(type default)
			)
			(layer "F.Fab")
		)
		(fp_line
			(start 0.67945 0.3048)
			(end 0.120396 0.3048)
			(stroke
				(width 0.1)
				(type default)
			)
			(layer "F.Fab")
		)
		(pad "1" smd circle
			(at -0.40005 0)
			(size 0 0)
			(layers "F.Cu" "F.Mask" "F.Paste")
			(net "PVCCINFAON_CPU0")
		)
		(pad "2" smd circle
			(at 0.40005 0)
			(size 0 0)
			(layers "F.Cu" "F.Mask" "F.Paste")
			(net "GND")
		)
	)
)
